# T6G (Grand Teton) — schematic parts with pin connectivity, parts 8231–8231 of 8303; source: Cadence DE-HDL packaged netlist (pstxprt.dat, pstxnet.dat, pstchip.dat)

U6014  PT5161LRS  IC  pkg BGA354_8-9X22-8  page 318
  A1  NCF_GND1  POWER  = NCF_A1_CPU1_P0_GND
  A35  NCF_GND2  POWER  = NCF_CPU1_P0_GND
  AA10  B_PETN1  OUT  = P5E_CPU1_P0_TX_BUF_DN<14>
  AA29  A_PETN1  OUT  = P5E_CPU1_P0_RX_DN<14>
  AB1  A_PERP1  IN  = P5E_CPU1_P0_RX_BUF_DP<14>
  AB35  B_PERN1  IN  = P5E_CPU1_P0_TX_C_DP<14>
  AC4  GND4  POWER  = GND
  AC13  GND1  POWER  = GND
  AC17  PWR_2A_1  POWER  = P0V9_CPU1_RT0_2A
  AC20  PWR_2A_2  POWER  = P0V9_CPU1_RT0_2A
  AC22  GND2  POWER  = GND
  AC32  GND3  POWER  = GND
  AD2  GND5  POWER  = GND
  AD34  GND6  POWER  = GND
  AE1  GND7  POWER  = GND
  AE35  GND8  POWER  = GND
  AF7  B_PETP2  OUT  = P5E_CPU1_P0_TX_BUF_DP<13>
  AF26  A_PETP2  OUT  = P5E_CPU1_P0_RX_DP<13>
  AG2  A_PERN2  IN  = P5E_CPU1_P0_RX_BUF_DN<13>
  AG34  B_PERP2  IN  = P5E_CPU1_P0_TX_C_DP<13>
  AH10  B_PETN2  OUT  = P5E_CPU1_P0_TX_BUF_DN<13>
  AH29  A_PETN2  OUT  = P5E_CPU1_P0_RX_DN<13>
  AJ1  A_PERP2  IN  = P5E_CPU1_P0_RX_BUF_DP<13>
  AJ35  B_PERN2  IN  = P5E_CPU1_P0_TX_C_DN<13>
  AK4  GND12  POWER  = GND
  AK13  GND9  POWER  = GND
  AK17  PWR_2A_3  POWER  = P0V9_CPU1_RT0_2A
  AK20  PWR_2A_4  POWER  = P0V9_CPU1_RT0_2A
  AK22  GND10  POWER  = GND
  AK32  GND11  POWER  = GND
  AL2  GND13  POWER  = GND
  AL34  GND14  POWER  = GND
  AM1  GND15  POWER  = GND
  AM35  GND16  POWER  = GND
  AN7  B_PETP3  OUT  = P5E_CPU1_P0_TX_BUF_DP<12>
  AN26  A_PETP3  OUT  = P5E_CPU1_P0_RX_DP<12>
  AP2  A_PERN3  IN  = P5E_CPU1_P0_RX_BUF_DN<12>
  AP34  B_PERP3  IN  = P5E_CPU1_P0_TX_C_DN<12>
  AR10  B_PETN3  OUT  = P5E_CPU1_P0_TX_BUF_DN<12>
  AR29  A_PETN3  OUT  = P5E_CPU1_P0_RX_DN<12>
  AT1  A_PERP3  IN  = P5E_CPU1_P0_RX_BUF_DP<12>
  AT35  B_PERN3  IN  = P5E_CPU1_P0_TX_C_DP<12>
  AU4  GND20  POWER  = GND
  AU13  GND17  POWER  = GND
  AU17  PWR_2A_5  POWER  = P0V9_CPU1_RT0_2A
  AU20  PWR_2A_6  POWER  = P0V9_CPU1_RT0_2A
  AU22  GND18  POWER  = GND
  AU32  GND19  POWER  = GND
  AV2  GND21  POWER  = GND
  AV34  GND22  POWER  = GND
  AW1  GND23  POWER  = GND
  AW35  GND24  POWER  = GND
  AY7  B_PETP4  OUT  = P5E_CPU1_P0_TX_BUF_DP<11>
  AY26  A_PETP4  OUT  = P5E_CPU1_P0_RX_DP<11>
  B3  JTAG_TCK  IN  = JTAG_TCK_RT_CPU1_P0
  B6  JTAG_TDI  IN  = JTAG_TDI_RT_CPU1_P0
  B9  JTAG_TDO  OUT  = JTAG_TDO_RT_CPU1_P0
  B12  JTAG_TMS  IN  = JTAG_TMS_RT_CPU1_P0
  B16  REFCLK_OUTP  OUT  = NC
  B19  GND25  POWER  = GND
  B23  SMB_ADDR2  IN  = RT_CPU1_P0_ADDR2
  B25  SMB_ADDR3  IN  = RT_CPU1_P0_ADDR3
  B28  SMBDAT  BI  = SMB_RT_CPU1_P0_R2_SDA
  B31  SMBCLK  BI  = SMB_RT_CPU1_P0_R2_SCL
  BA2  A_PERN4  IN  = P5E_CPU1_P0_RX_BUF_DN<11>
  BA34  B_PERP4  IN  = P5E_CPU1_P0_TX_C_DN<11>
  BB10  B_PETN4  OUT  = P5E_CPU1_P0_TX_BUF_DN<11>
  BB29  A_PETN4  OUT  = P5E_CPU1_P0_RX_DN<11>
  BC1  A_PERP4  IN  = P5E_CPU1_P0_RX_BUF_DP<11>
  BC35  B_PERN4  IN  = P5E_CPU1_P0_TX_C_DP<11>
  BD4  GND29  POWER  = GND
  BD13  GND26  POWER  = GND
  BD17  PWR_2A_7  POWER  = P0V9_CPU1_RT0_2A_2D
  BD20  PWR_2A_8  POWER  = P0V9_CPU1_RT0_2A_2D
  BD22  GND27  POWER  = GND
  BD32  GND28  POWER  = GND
  BE2  GND30  POWER  = GND
  BE34  GND31  POWER  = GND
  BF1  GND32  POWER  = GND
  BF35  GND33  POWER  = GND
  BG7  B_PETP5  OUT  = P5E_CPU1_P0_TX_BUF_DP<10>
  BG26  A_PETP5  OUT  = P5E_CPU1_P0_RX_DP<10>
  BH2  A_PERN5  IN  = P5E_CPU1_P0_RX_BUF_DN<10>
  BH34  B_PERP5  IN  = P5E_CPU1_P0_TX_C_DN<10>
  BJ10  B_PETN5  OUT  = P5E_CPU1_P0_TX_BUF_DN<10>
  BJ29  A_PETN5  OUT  = P5E_CPU1_P0_RX_DN<10>
  BK1  A_PERP5  IN  = P5E_CPU1_P0_RX_BUF_DP<10>
  BK35  B_PERN5  IN  = P5E_CPU1_P0_TX_C_DP<10>
  BL4  GND37  POWER  = GND
  BL13  GND34  POWER  = GND
  BL17  PWR_2D_1  POWER  = P0V9_CPU1_RT_2D
  BL20  PWR_2D_2  POWER  = P0V9_CPU1_RT_2D
  BL22  GND35  POWER  = GND
  BL32  GND36  POWER  = GND
  BM2  GND38  POWER  = GND
  BM34  GND39  POWER  = GND
  BN1  GND40  POWER  = GND
  BN35  GND41  POWER  = GND
  BP7  B_PETP6  OUT  = P5E_CPU1_P0_TX_BUF_DP<9>
  BP26  A_PETP6  OUT  = P5E_CPU1_P0_RX_DP<9>
  BR2  A_PERN6  IN  = P5E_CPU1_P0_RX_BUF_DN<9>
  BR34  B_PERP6  IN  = P5E_CPU1_P0_TX_C_DN<9>
  BT10  B_PETN6  OUT  = P5E_CPU1_P0_TX_BUF_DN<9>
  BT29  A_PETN6  OUT  = P5E_CPU1_P0_RX_DN<9>
  BU1  A_PERP6  IN  = P5E_CPU1_P0_RX_BUF_DP<9>
  BU35  B_PERN6  IN  = P5E_CPU1_P0_TX_C_DP<9>
  BV4  GND45  POWER  = GND
  BV13  GND42  POWER  = GND
  BV17  PWR_1D  POWER  = P1V8_CPU1_RT0_1A_1D
  BV20  PWR_1A_1  POWER  = P1V8_CPU1_RT0_1A
  BV22  GND43  POWER  = GND
  BV32  GND44  POWER  = GND
  BW2  GND46  POWER  = GND
  BW34  GND47  POWER  = GND
  BY1  GND48  POWER  = GND
  BY35  GND49  POWER  = GND
  C2  NCF_GND3  POWER  = NCF_CPU1_P0_GND
  C34  NCF_GND4  POWER  = NCF_CPU1_P0_GND
  CA7  B_PETP7  OUT  = P5E_CPU1_P0_TX_BUF_DP<8>
  CA26  A_PETP7  OUT  = P5E_CPU1_P0_RX_DP<8>
  CB2  A_PERN7  IN  = P5E_CPU1_P0_RX_BUF_DN<8>
  CB34  B_PERP7  IN  = P5E_CPU1_P0_TX_C_DN<8>
  CC10  B_PETN7  OUT  = P5E_CPU1_P0_TX_BUF_DN<8>
  CC29  A_PETN7  OUT  = P5E_CPU1_P0_RX_DN<8>
  CD1  A_PERP7  IN  = P5E_CPU1_P0_RX_BUF_DP<8>
  CD35  B_PERN7  IN  = P5E_CPU1_P0_TX_C_DP<8>
  CE4  GND53  POWER  = GND
  CE13  GND50  POWER  = GND
  CE17  PWR_1A_2  POWER  = P1V8_CPU1_RT0_1A
  CE20  PWR_1A_3  POWER  = P1V8_CPU1_RT0_1A
  CE22  GND51  POWER  = GND
  CE32  GND52  POWER  = GND
  CF2  GND54  POWER  = GND
  CF34  GND55  POWER  = GND
  CG1  GND56  POWER  = GND
  CG35  GND57  POWER  = GND
  CH7  B_PETP8  OUT  = P5E_CPU1_P0_TX_BUF_DP<7>
  CH26  A_PETP8  OUT  = P5E_CPU1_P0_RX_DP<7>
  CJ2  A_PERN8  IN  = P5E_CPU1_P0_RX_BUF_DN<7>
  CJ34  B_PERP8  IN  = P5E_CPU1_P0_TX_C_DN<7>
  CK10  B_PETN8  OUT  = P5E_CPU1_P0_TX_BUF_DN<7>
  CK29  A_PETN8  OUT  = P5E_CPU1_P0_RX_DN<7>
  CL1  A_PERP8  IN  = P5E_CPU1_P0_RX_BUF_DP<7>
  CL35  B_PERN8  IN  = P5E_CPU1_P0_TX_C_DP<7>
  CM4  GND61  POWER  = GND
  CM13  GND58  POWER  = GND
  CM17  PWR_1A_4  POWER  = P1V8_CPU1_RT0_1A
  CM20  PWR_1A_5  POWER  = P1V8_CPU1_RT0_1A
  CM22  GND59  POWER  = GND
  CM32  GND60  POWER  = GND
  CN2  GND62  POWER  = GND
  CN34  GND63  POWER  = GND
  CP1  GND64  POWER  = GND
  CP35  GND65  POWER  = GND
  CR7  B_PETP9  OUT  = P5E_CPU1_P0_TX_BUF_DP<6>
  CR26  A_PETP9  OUT  = P5E_CPU1_P0_RX_DP<6>
  CT2  A_PERN9  IN  = P5E_CPU1_P0_RX_BUF_DN<6>
  CT34  B_PERP9  IN  = P5E_CPU1_P0_TX_C_DN<6>
  CU10  B_PETN9  OUT  = P5E_CPU1_P0_TX_BUF_DN<6>
  CU29  A_PETN9  OUT  = P5E_CPU1_P0_RX_DN<6>
  CV1  A_PERP9  IN  = P5E_CPU1_P0_RX_BUF_DP<6>
  CV35  B_PERN9  IN  = P5E_CPU1_P0_TX_C_DP<6>
  CW4  GND69  POWER  = GND
  CW13  GND66  POWER  = GND
  CW17  PWR_2D_3  POWER  = P0V9_CPU1_RT_2D
  CW20  PWR_2D_4  POWER  = P0V9_CPU1_RT_2D
  CW22  GND67  POWER  = GND
  CW32  GND68  POWER  = GND
  CY2  GND70  POWER  = GND
  CY34  GND71  POWER  = GND
  D1  NCF_GND5  POWER  = NCF_CPU1_P0_GND
  D35  NCF_GND6  POWER  = NCF_CPU1_P0_GND
  DA1  GND72  POWER  = GND
  DA35  GND73  POWER  = GND
  DB7  B_PETP10  OUT  = P5E_CPU1_P0_TX_BUF_DP<5>
  DB26  A_PETP10  OUT  = P5E_CPU1_P0_RX_DP<5>
  DC2  A_PERN10  IN  = P5E_CPU1_P0_RX_BUF_DN<5>
  DC34  B_PERP10  IN  = P5E_CPU1_P0_TX_C_DN<5>
  DD10  B_PETN10  OUT  = P5E_CPU1_P0_TX_BUF_DN<5>
  DD29  A_PETN10  OUT  = P5E_CPU1_P0_RX_DN<5>
  DE1  A_PERP10  IN  = P5E_CPU1_P0_RX_BUF_DP<5>
  DE35  B_PERN10  IN  = P5E_CPU1_P0_TX_C_DP<5>
  DF4  GND77  POWER  = GND
  DF13  GND74  POWER  = GND
  DF17  PWR_2A_9  POWER  = P0V9_CPU1_RT0_2A_2D
  DF20  PWR_2A_10  POWER  = P0V9_CPU1_RT0_2A_2D
  DF22  GND75  POWER  = GND
  DF32  GND76  POWER  = GND
  DG2  GND78  POWER  = GND
  DG34  GND79  POWER  = GND
  DH1  GND80  POWER  = GND
  DH35  GND81  POWER  = GND
  DJ7  B_PETP11  OUT  = P5E_CPU1_P0_TX_BUF_DP<4>
  DJ26  A_PETP11  OUT  = P5E_CPU1_P0_RX_DP<4>
  DK2  A_PERN11  IN  = P5E_CPU1_P0_RX_BUF_DN<4>
  DK34  B_PERP11  IN  = P5E_CPU1_P0_TX_C_DN<4>
  DL10  B_PETN11  OUT  = P5E_CPU1_P0_TX_BUF_DN<4>
  DL29  A_PETN11  OUT  = P5E_CPU1_P0_RX_DN<4>
  DM1  A_PERP11  IN  = P5E_CPU1_P0_RX_BUF_DP<4>
  DM35  B_PERN11  IN  = P5E_CPU1_P0_TX_C_DP<4>
  DN4  GND85  POWER  = GND
  DN13  GND82  POWER  = GND
  DN17  PWR_2A_11  POWER  = P0V9_CPU1_RT0_2A
  DN20  PWR_2A_12  POWER  = P0V9_CPU1_RT0_2A
  DN22  GND83  POWER  = GND
  DN32  GND84  POWER  = GND
  DP2  GND86  POWER  = GND
  DP34  GND87  POWER  = GND
  DR1  GND88  POWER  = GND
  DR35  GND89  POWER  = GND
  DT7  B_PETP12  OUT  = P5E_CPU1_P0_TX_BUF_DP<3>
  DT26  A_PETP12  OUT  = P5E_CPU1_P0_RX_DP<3>
  DU2  A_PERN12  IN  = P5E_CPU1_P0_RX_BUF_DN<3>
  DU34  B_PERP12  IN  = P5E_CPU1_P0_TX_C_DN<3>
  DV10  B_PETN12  OUT  = P5E_CPU1_P0_TX_BUF_DN<3>
  DV29  A_PETN12  OUT  = P5E_CPU1_P0_RX_DN<3>
  DW1  A_PERP12  IN  = P5E_CPU1_P0_RX_BUF_DP<3>
  DW35  B_PERN12  IN  = P5E_CPU1_P0_TX_C_DP<3>
  DY4  GND93  POWER  = GND
  DY13  GND90  POWER  = GND
  DY17  PWR_2A_13  POWER  = P0V9_CPU1_RT0_2A
  DY20  PWR_2A_14  POWER  = P0V9_CPU1_RT0_2A
  DY22  GND91  POWER  = GND
  DY32  GND92  POWER  = GND
  E8  JTAG_TRST_N  IN  = JTAG_TRST_RT_CPU1_P0_N
  E11  RXDET_BYP  IN  = RXDET_BYP_RT_CPU1_P0
  E14  GND94  POWER  = GND
  E18  REFCLK_OUTN  OUT  = NC
  E27  GND95  POWER  = GND
  E30  T_SENSE  OUT  = GND
  E33  GND96  POWER  = GND
  EA2  GND97  POWER  = GND
  EA34  GND98  POWER  = GND
  EB1  GND99  POWER  = GND
  EB35  GND100  POWER  = GND
  EC7  B_PETP13  OUT  = P5E_CPU1_P0_TX_BUF_DP<2>
  EC26  A_PETP13  OUT  = P5E_CPU1_P0_RX_DP<2>
  ED2  A_PERN13  IN  = P5E_CPU1_P0_RX_BUF_DN<2>
  ED34  B_PERP13  IN  = P5E_CPU1_P0_TX_C_DN<2>
  EE10  B_PETN13  OUT  = P5E_CPU1_P0_TX_BUF_DN<2>
  EE29  A_PETN13  OUT  = P5E_CPU1_P0_RX_DN<2>
  EF1  A_PERP13  IN  = P5E_CPU1_P0_RX_BUF_DP<2>
  EF35  B_PERN13  IN  = P5E_CPU1_P0_TX_C_DP<2>
  EG4  GND104  POWER  = GND
  EG13  GND101  POWER  = GND
  EG17  PWR_2A_15  POWER  = P0V9_CPU1_RT0_2A
  EG20  PWR_2A_16  POWER  = P0V9_CPU1_RT0_2A
  EG22  GND102  POWER  = GND
  EG32  GND103  POWER  = GND
  EH2  GND105  POWER  = GND
  EH34  GND106  POWER  = GND
  EJ1  GND107  POWER  = GND
  EJ35  GND108  POWER  = GND
  EK7  B_PETP14  OUT  = P5E_CPU1_P0_TX_BUF_DP<1>
  EK26  A_PETP14  OUT  = P5E_CPU1_P0_RX_DP<1>
  EL2  A_PERN14  IN  = P5E_CPU1_P0_RX_BUF_DN<1>
  EL34  B_PERP14  IN  = P5E_CPU1_P0_TX_C_DP<1>
  EM10  B_PETN14  OUT  = P5E_CPU1_P0_TX_BUF_DN<1>
  EM29  A_PETN14  OUT  = P5E_CPU1_P0_RX_DN<1>
  EN1  A_PERP14  IN  = P5E_CPU1_P0_RX_BUF_DP<1>
  EN35  B_PERN14  IN  = P5E_CPU1_P0_TX_C_DN<1>
  EP4  GND112  POWER  = GND
  EP13  GND109  POWER  = GND
  EP17  PWR_2A_17  POWER  = P0V9_CPU1_RT0_2A
  EP20  PWR_2A_18  POWER  = P0V9_CPU1_RT0_2A
  EP22  GND110  POWER  = GND
  EP32  GND111  POWER  = GND
  ER2  GND113  POWER  = GND
  ER34  GND114  POWER  = GND
  ET1  GND115  POWER  = GND
  ET35  GND116  POWER  = GND
  EU7  B_PETP15  OUT  = P5E_CPU1_P0_TX_BUF_DP<0>
  EU26  A_PETP15  OUT  = P5E_CPU1_P0_RX_DP<0>
  EV2  A_PERN15  IN  = P5E_CPU1_P0_RX_BUF_DN<0>
  EV34  B_PERP15  IN  = P5E_CPU1_P0_TX_C_DN<0>
  EW10  B_PETN15  OUT  = P5E_CPU1_P0_TX_BUF_DN<0>
  EW29  A_PETN15  OUT  = P5E_CPU1_P0_RX_DN<0>
  EY1  A_PERP15  IN  = P5E_CPU1_P0_RX_BUF_DP<0>
  EY35  B_PERN15  IN  = P5E_CPU1_P0_TX_C_DP<0>
  F2  PERST_N  IN  = RST_RT_CPU1_P0_PERST_N
  F34  SMB_ADDR1  IN  = RT_CPU1_P0_ADDR1
  FA15  GND117  POWER  = GND
  FA32  GND118  POWER  = GND
  FB2  GND119  POWER  = GND
  FB34  GND120  POWER  = GND
  FC3  GND125  POWER  = GND
  FC6  GND126  POWER  = GND
  FC9  GND127  POWER  = GND
  FC19  GND121  POWER  = GND
  FC23  GND122  POWER  = GND
  FC25  GND123  POWER  = GND
  FC28  GND124  POWER  = GND
  FD1  GND128  POWER  = GND
  FD35  GND129  POWER  = GND
  FE2  NCF_GND7  POWER  = NCF_CPU1_P0_GND
  FE34  NCF_GND8  POWER  = NCF_CPU1_P0_GND
  FF5  EE_CLK  BI  = SMB_RT_CPU1_P0_ROM_MUX_1D_R_SCL
  FF8  JTAG_TEST_MODE  IN  = JTAG_TEST_MODE_RT_CPU1_P0
  FF11  RESET_N  IN  = RST_RT_CPU1_P0_RESET_N
  FF14  GND130  POWER  = GND
  FF18  REFCLKN  IN  = CLK_100M_RETIMER_CPU1_P0_DN
  FF21  GND131  POWER  = GND
  FF24  TEST0  BI  = TEST0_RT_CPU1_P0
  FF27  TEST1  BI  = TEST1_RT_CPU1_P0
  FF30  TEST2  BI  = TEST2_RT_CPU1_P0
  FF33  SCAN_MODE  IN  = RT_CPU1_P0_SCAN_MODE
  FG1  NCF_GND9  POWER  = NCF_CPU1_P0_GND
  FG35  NCF_GND10  POWER  = NCF_CPU1_P0_GND
  FH2  NCF_GND11  POWER  = NCF_CPU1_P0_GND
  FH34  NCF_GND12  POWER  = NCF_CPU1_P0_GND
  FJ3  EE_DAT  BI  = SMB_RT_CPU1_P0_ROM_MUX_1D_R_SDA
  FJ6  GPIO0  BI  = NC
  FJ9  MODE  IN  = MODE_RT_CPU1_P0
  FJ12  GND132  POWER  = GND
  FJ16  REFCLKP  IN  = CLK_100M_RETIMER_CPU1_P0_DP
  FJ19  GND133  POWER  = GND
  FJ23  GPIO1  BI  = NC
  FJ25  GPIO2  BI  = GPIO2_RT_CPU1_P0
  FJ28  GPIO3  BI  = GPIO3_RT_CPU1_P0
  FJ31  INT_N  OUT  = NC
  G1  VQPS  IN  = RT_CPU1_P0_VQPS
  G35  CLKREQ_N  IN  = CLKREQ_RT_CPU1_P0_N
  H12  GND134  POWER  = GND
  H16  GND135  POWER  = GND
  H19  GND136  POWER  = GND
  H31  GND137  POWER  = GND
  J4  GND139  POWER  = GND
  J22  GND138  POWER  = GND
  K2  GND140  POWER  = GND
  K34  GND141  POWER  = GND
  L1  GND142  POWER  = GND
  L35  GND143  POWER  = GND
  M7  B_PETP0  OUT  = P5E_CPU1_P0_TX_BUF_DP<15>
  M26  A_PETP0  OUT  = P5E_CPU1_P0_RX_DP<15>
  N2  A_PERN0  IN  = P5E_CPU1_P0_RX_BUF_DN<15>
  N34  B_PERP0  IN  = P5E_CPU1_P0_TX_C_DN<15>
  P10  B_PETN0  OUT  = P5E_CPU1_P0_TX_BUF_DN<15>
  P29  A_PETN0  OUT  = P5E_CPU1_P0_RX_DN<15>
  R1  A_PERP0  IN  = P5E_CPU1_P0_RX_BUF_DP<15>
  R35  B_PERN0  IN  = P5E_CPU1_P0_TX_C_DP<15>
  T4  GND147  POWER  = GND
  T13  GND144  POWER  = GND
  T17  PWR_2A_19  POWER  = P0V9_CPU1_RT0_2A
  T20  PWR_2A_20  POWER  = P0V9_CPU1_RT0_2A
  T22  GND145  POWER  = GND
  T32  GND146  POWER  = GND
  U2  GND148  POWER  = GND
  U34  GND149  POWER  = GND
  V1  GND150  POWER  = GND
  V35  GND151  POWER  = GND
  W7  B_PETP1  OUT  = P5E_CPU1_P0_TX_BUF_DP<14>
  W26  A_PETP1  OUT  = P5E_CPU1_P0_RX_DP<14>
  Y2  A_PERN1  IN  = P5E_CPU1_P0_RX_BUF_DN<14>
  Y34  B_PERP1  IN  = P5E_CPU1_P0_TX_C_DN<14>
